# T6G (Grand Teton) — schematic netlist excerpt (pin names and nets, part order shuffled) for the footprints in the layout excerpt that follows; sources: Cadence DE-HDL packaged netlist, KiCad conversion of 04192023_DAF0TMB3IC0_F0TG_MB_C_brd_V02_OCP.brd

C842  Q_CAP_DIFFBUS  DIFF BUS_0.22UF 6.3V 20% X6S  pkg C0201  page 64 : \1\ = P5E_CPU0_P2_TX_C_DN<13> ; \2\ = P5E_CPU0_P2_TX_DN<13>

U167  NCP698SQ15T1G  EMPTY  pkg SC82-AB-4_1-3_2X1-25  page 187
  GND  = GND
  VIN  = P1V5_BAT_IN
  VOUT  = P1V5_BAT_OUT
  EN  = BAT_LDO_EN

R8121  Q_RES  17.8K 1% CHIP  pkg 0402LF  page 268 : A = P12V_AUX ; B = P12V_AUX_UV_TRIGGER

(kicad_pcb
	(version 20260206)
	(generator "pcbnew")
	(generator_version "10.0")
	(general
		(thickness 1.6)
		(legacy_teardrops no)
	)
	(paper "A4")
	(title_block
		(title "04192023_DAF0TMB3IC0_F0TG_MB_C_brd_V02_OCP.brd")
		(comment 1 "Grand Teton / footprints 3142-3144 of 8354")
	)
	(layers
		(0 "F.Cu" signal "TOP")
		(4 "In1.Cu" signal "GND")
		(6 "In2.Cu" signal "IN1")
		(8 "In3.Cu" signal "GND1")
		(10 "In4.Cu" signal "IN2")
		(12 "In5.Cu" signal "GND2")
		(14 "In6.Cu" signal "IN3")
		(16 "In7.Cu" signal "GND3")
		(18 "In8.Cu" signal "VCC")
		(20 "In9.Cu" signal "VCC1")
		(22 "In10.Cu" signal "GND4")
		(24 "In11.Cu" signal "IN4")
		(26 "In12.Cu" signal "GND5")
		(28 "In13.Cu" signal "IN5")
		(30 "In14.Cu" signal "GND6")
		(32 "In15.Cu" signal "IN6")
		(34 "In16.Cu" signal "GND7")
		(2 "B.Cu" signal "BOTTOM")
		(9 "F.Adhes" user "F.Adhesive")
		(11 "B.Adhes" user "B.Adhesive")
		(13 "F.Paste" user "Package Geometry/Pastemask Top")
		(15 "B.Paste" user "Package Geometry/Pastemask Bottom")
		(5 "F.SilkS" user "Ref Des/Silkscreen Top")
		(7 "B.SilkS" user "Ref Des/Silkscreen Bottom")
		(1 "F.Mask" user "Board Geometry/Soldermask Top")
		(3 "B.Mask" user "Board Geometry/Soldermask Bottom")
		(17 "Dwgs.User" user "User.Drawings")
		(19 "Cmts.User" user "User.Comments")
		(21 "Eco1.User" user "User.Eco1")
		(23 "Eco2.User" user "User.Eco2")
		(25 "Edge.Cuts" user "Board Geometry/Outline")
		(27 "Margin" user)
		(31 "F.CrtYd" user "Package Geometry/Place Bound Top")
		(29 "B.CrtYd" user "Package Geometry/Place Bound Bottom")
		(35 "F.Fab" user "Ref Des/Assembly Top")
		(33 "B.Fab" user "Ref Des/Assembly Bottom")
	)
	(footprint ""
		(layer "F.Cu")
		(at 298.300902 -20.255992 -90)
		(property "Reference" "U167"
			(at -0.130556 1.749552 90)
			(unlocked yes)
			(layer "F.SilkS")
			(effects
				(font
					(size 0.7874 0.5842)
					(thickness 0.1524)
				)
				(justify left)
			)
		)
		(property "Value" ""
			(at 0 0 270)
			(layer "F.Fab")
			(effects
				(font
					(size 1.27 1.27)
				)
			)
		)
		(duplicate_pad_numbers_are_jumpers no)
		(fp_line
			(start -1.538478 1.150874)
			(end 1.538478 1.150874)
			(stroke
				(width 0.1524)
				(type default)
			)
			(layer "F.SilkS")
		)
		(fp_line
			(start 1.538478 1.150874)
			(end 1.538478 -1.150874)
			(stroke
				(width 0.1524)
				(type default)
			)
			(layer "F.SilkS")
		)
		(fp_line
			(start -1.538478 -1.150874)
			(end -1.538478 1.150874)
			(stroke
				(width 0.1524)
				(type default)
			)
			(layer "F.SilkS")
		)
		(fp_line
			(start 1.538478 -1.150874)
			(end -1.538478 -1.150874)
			(stroke
				(width 0.1524)
				(type default)
			)
			(layer "F.SilkS")
		)
		(fp_poly
			(pts
				(xy -1.378966 -1.298448) (xy -2.187194 -1.567942) (xy -1.648206 -2.106676)
			)
			(stroke
				(width 0)
				(type default)
			)
			(fill yes)
			(layer "F.SilkS")
		)
		(fp_line
			(start -0.674878 1.100074)
			(end 0.674878 1.100074)
			(stroke
				(width 0.1)
				(type default)
			)
			(layer "F.Fab")
		)
		(fp_line
			(start 0.674878 1.100074)
			(end 0.674878 -1.100074)
			(stroke
				(width 0.1)
				(type default)
			)
			(layer "F.Fab")
		)
		(fp_line
			(start -0.674878 -1.100074)
			(end -0.674878 1.100074)
			(stroke
				(width 0.1)
				(type default)
			)
			(layer "F.Fab")
		)
		(fp_line
			(start 0.674878 -1.100074)
			(end -0.674878 -1.100074)
			(stroke
				(width 0.1)
				(type default)
			)
			(layer "F.Fab")
		)
		(fp_poly
			(pts
				(xy -2.4384 -1.030986) (xy -2.4384 -0.268986) (xy -1.6764 -0.649986)
			)
			(stroke
				(width 0)
				(type default)
			)
			(fill yes)
			(layer "F.Fab")
		)
		(pad "1" smd rect
			(at -0.94996 -0.649986 180)
			(size 0.7112 0.9144)
			(layers "F.Cu" "F.Mask" "F.Paste")
			(net "GND")
		)
		(pad "2" smd rect
			(at -0.94996 0.649986 180)
			(size 0.7112 0.9144)
			(layers "F.Cu" "F.Mask" "F.Paste")
			(net "P1V5_BAT_IN")
		)
		(pad "3" smd rect
			(at 0.94996 0.649986 180)
			(size 0.7112 0.9144)
			(layers "F.Cu" "F.Mask" "F.Paste")
			(net "P1V5_BAT_OUT")
		)
		(pad "4" smd rect
			(at 0.94996 -0.649986 180)
			(size 0.7112 0.9144)
			(layers "F.Cu" "F.Mask" "F.Paste")
			(net "BAT_LDO_EN")
		)
	)
	(footprint ""
		(layer "F.Cu")
		(at 425.05884 -378.95403 -90)
		(property "Reference" "C842"
			(at 0 0 270)
			(layer "F.SilkS")
			(hide yes)
			(effects
				(font
					(size 1.27 1.27)
				)
			)
		)
		(property "Value" ""
			(at 0 0 270)
			(layer "F.Fab")
			(effects
				(font
					(size 1.27 1.27)
				)
			)
		)
		(duplicate_pad_numbers_are_jumpers no)
		(fp_line
			(start -0.299974 0.150114)
			(end -0.299974 -0.150114)
			(stroke
				(width 0.1)
				(type default)
			)
			(layer "F.Fab")
		)
		(fp_line
			(start 0.299974 0.150114)
			(end -0.299974 0.150114)
			(stroke
				(width 0.1)
				(type default)
			)
			(layer "F.Fab")
		)
		(fp_line
			(start -0.299974 -0.150114)
			(end 0.299974 -0.150114)
			(stroke
				(width 0.1)
				(type default)
			)
			(layer "F.Fab")
		)
		(fp_line
			(start 0.299974 -0.150114)
			(end 0.299974 0.150114)
			(stroke
				(width 0.1)
				(type default)
			)
			(layer "F.Fab")
		)
		(pad "1" smd rect
			(at -0.2667 0 270)
			(size 0.3048 0.381)
			(layers "F.Cu" "F.Mask" "F.Paste")
			(net "P5E_CPU0_P2_TX_C_DN<13>")
		)
		(pad "2" smd rect
			(at 0.2667 0 270)
			(size 0.3048 0.381)
			(layers "F.Cu" "F.Mask" "F.Paste")
			(net "P5E_CPU0_P2_TX_DN<13>")
		)
	)
	(footprint ""
		(layer "F.Cu")
		(at 145.669 -115.443 180)
		(property "Reference" "R8121"
			(at 0 0 180)
			(layer "F.SilkS")
			(hide yes)
			(effects
				(font
					(size 1.27 1.27)
				)
			)
		)
		(property "Value" ""
			(at 0 0 180)
			(layer "F.Fab")
			(effects
				(font
					(size 1.27 1.27)
				)
			)
		)
		(duplicate_pad_numbers_are_jumpers no)
		(fp_line
			(start 0.7874 0.4064)
			(end -0.7874 0.4064)
			(stroke
				(width 0.1524)
				(type default)
			)
			(layer "F.SilkS")
		)
		(fp_line
			(start 0.7874 -0.4064)
			(end 0.7874 0.4064)
			(stroke
				(width 0.1524)
				(type default)
			)
			(layer "F.SilkS")
		)
		(fp_line
			(start -0.7874 0.4064)
			(end -0.7874 -0.4064)
			(stroke
				(width 0.1524)
				(type default)
			)
			(layer "F.SilkS")
		)
		(fp_line
			(start -0.7874 -0.4064)
			(end 0.7874 -0.4064)
			(stroke
				(width 0.1524)
				(type default)
			)
			(layer "F.SilkS")
		)
		(fp_line
			(start 0.67945 0.3048)
			(end 0.120396 0.3048)
			(stroke
				(width 0.1)
				(type default)
			)
			(layer "F.Fab")
		)
		(fp_line
			(start 0.67945 -0.3048)
			(end 0.67945 0.3048)
			(stroke
				(width 0.1)
				(type default)
			)
			(layer "F.Fab")
		)
		(fp_line
			(start 0.12065 -0.2794)
			(end 0.12065 -0.3048)
			(stroke
				(width 0.1)
				(type default)
			)
			(layer "F.Fab")
		)
		(fp_line
			(start 0.12065 -0.3048)
			(end 0.67945 -0.3048)
			(stroke
				(width 0.1)
				(type default)
			)
			(layer "F.Fab")
		)
		(fp_line
			(start 0.120396 0.3048)
			(end 0.120396 0.2794)
			(stroke
				(width 0.1)
				(type default)
			)
			(layer "F.Fab")
		)
		(fp_line
			(start 0.120396 0.2794)
			(end -0.12065 0.2794)
			(stroke
				(width 0.1)
				(type default)
			)
			(layer "F.Fab")
		)
		(fp_line
			(start -0.12065 0.3048)
			(end -0.67945 0.3048)
			(stroke
				(width 0.1)
				(type default)
			)
			(layer "F.Fab")
		)
		(fp_line
			(start -0.12065 0.2794)
			(end -0.12065 0.3048)
			(stroke
				(width 0.1)
				(type default)
			)
			(layer "F.Fab")
		)
		(fp_line
			(start -0.12065 -0.2794)
			(end 0.12065 -0.2794)
			(stroke
				(width 0.1)
				(type default)
			)
			(layer "F.Fab")
		)
		(fp_line
			(start -0.12065 -0.305054)
			(end -0.12065 -0.2794)
			(stroke
				(width 0.1)
				(type default)
			)
			(layer "F.Fab")
		)
		(fp_line
			(start -0.67945 0.3048)
			(end -0.67945 -0.305054)
			(stroke
				(width 0.1)
				(type default)
			)
			(layer "F.Fab")
		)
		(fp_line
			(start -0.67945 -0.305054)
			(end -0.12065 -0.305054)
			(stroke
				(width 0.1)
				(type default)
			)
			(layer "F.Fab")
		)
		(pad "1" smd circle
			(at -0.40005 0 180)
			(size 0 0)
			(layers "F.Cu" "F.Mask" "F.Paste")
			(net "P12V_AUX")
		)
		(pad "2" smd circle
			(at 0.40005 0 180)
			(size 0 0)
			(layers "F.Cu" "F.Mask" "F.Paste")
			(net "P12V_AUX_UV_TRIGGER")
		)
	)
)
